(kicad_pcb
	(version 20260206)
	(generator "pcbnew")
	(generator_version "10.0")
	(general
		(thickness 1.6)
		(legacy_teardrops no)
	)
	(paper "A4")
	(title_block
		(title "timecard-production-celestica-r4006 — R4006-B0001-02_R01.brd")
		(comment 1 "Time Appliance Project (Time Card) / footprints 767-771 of 1113")
	)
	(layers
		(0 "F.Cu" signal "TOP")
		(4 "In1.Cu" signal "L02_GND1")
		(6 "In2.Cu" signal "L03_SIG1")
		(8 "In3.Cu" signal "L04_GND2")
		(10 "In4.Cu" signal "L05_VCC1")
		(12 "In5.Cu" signal "L06_VCC2")
		(14 "In6.Cu" signal "L07_GND3")
		(16 "In7.Cu" signal "L08_SIG2")
		(18 "In8.Cu" signal "L09_GND4")
		(2 "B.Cu" signal "BOTTOM")
		(9 "F.Adhes" user "F.Adhesive")
		(11 "B.Adhes" user "B.Adhesive")
		(13 "F.Paste" user "Package Geometry/Pastemask Top")
		(15 "B.Paste" user "Package Geometry/Pastemask Bottom")
		(5 "F.SilkS" user "Ref Des/Silkscreen Top")
		(7 "B.SilkS" user "Ref Des/Silkscreen Bottom")
		(1 "F.Mask" user "Board Geometry/Soldermask Top")
		(3 "B.Mask" user "Board Geometry/Soldermask Bottom")
		(17 "Dwgs.User" user "User.Drawings")
		(19 "Cmts.User" user "User.Comments")
		(21 "Eco1.User" user "User.Eco1")
		(23 "Eco2.User" user "User.Eco2")
		(25 "Edge.Cuts" user "Board Geometry/Outline")
		(27 "Margin" user)
		(31 "F.CrtYd" user "Package Geometry/Place Bound Top")
		(29 "B.CrtYd" user "Package Geometry/Place Bound Bottom")
		(35 "F.Fab" user "Ref Des/Assembly Top")
		(33 "B.Fab" user "Ref Des/Assembly Bottom")
	)
	(footprint ""
		(layer "B.Cu")
		(at 139.954 -51.943 90)
		(property "Reference" "C265"
			(at -2.032 -1.18237 270)
			(unlocked yes)
			(layer "B.SilkS")
			(effects
				(font
					(size 0.7874 0.5842)
					(thickness 0.1524)
				)
				(justify mirror)
			)
		)
		(property "Value" "VAL*"
			(at -0.0762 2.067306 90)
			(unlocked yes)
			(layer "B.Fab")
			(hide yes)
			(effects
				(font
					(size 0.7874 0.5842)
					(thickness 0.1524)
				)
				(justify mirror)
			)
		)
		(property "Tolerance" "TOL*"
			(at -0.0762 3.032506 90)
			(unlocked yes)
			(layer "Cmts.User")
			(hide yes)
			(effects
				(font
					(size 0.7874 0.5842)
					(thickness 0.1524)
				)
				(justify mirror)
			)
		)
		(property "User Part Number" "PARTNUM*"
			(at -0.1016 4.023106 90)
			(unlocked yes)
			(layer "Cmts.User")
			(hide yes)
			(effects
				(font
					(size 0.7874 0.5842)
					(thickness 0.1524)
				)
				(justify mirror)
			)
		)
		(property "Device Type" "CAPACITOR-G105-0B104-EK,0.1UF,A"
			(at -0.0508 1.127506 90)
			(unlocked yes)
			(layer "B.Fab")
			(hide yes)
			(effects
				(font
					(size 0.7874 0.5842)
					(thickness 0.1524)
				)
				(justify mirror)
			)
		)
		(duplicate_pad_numbers_are_jumpers no)
		(fp_line
			(start 1.143 -0.5588)
			(end 1.143 0.5588)
			(stroke
				(width 0.1)
				(type default)
			)
			(layer "B.SilkS")
		)
		(fp_line
			(start -1.143 -0.5588)
			(end 1.143 -0.5588)
			(stroke
				(width 0.1)
				(type default)
			)
			(layer "B.SilkS")
		)
		(fp_line
			(start 1.143 0.5588)
			(end -1.143 0.5588)
			(stroke
				(width 0.1)
				(type default)
			)
			(layer "B.SilkS")
		)
		(fp_line
			(start -1.143 0.5588)
			(end -1.143 -0.5588)
			(stroke
				(width 0.1)
				(type default)
			)
			(layer "B.SilkS")
		)
		(fp_rect
			(start 1.143 -0.5588)
			(end -1.143 0.5588)
			(stroke
				(width 0)
				(type default)
			)
			(fill no)
			(layer "B.CrtYd")
		)
		(fp_line
			(start 0.508 -0.3048)
			(end 0.508 0.3048)
			(stroke
				(width 0.1)
				(type default)
			)
			(layer "B.Fab")
		)
		(fp_line
			(start -0.508 -0.3048)
			(end 0.508 -0.3048)
			(stroke
				(width 0.1)
				(type default)
			)
			(layer "B.Fab")
		)
		(fp_line
			(start 0.508 0.3048)
			(end -0.508 0.3048)
			(stroke
				(width 0.1)
				(type default)
			)
			(layer "B.Fab")
		)
		(fp_line
			(start -0.508 0.3048)
			(end -0.508 -0.3048)
			(stroke
				(width 0.1)
				(type default)
			)
			(layer "B.Fab")
		)
		(pad "1" smd rect
			(at 0.5334 0 270)
			(size 0.7112 0.6096)
			(layers "B.Cu" "B.Mask" "B.Paste")
			(net "UNNAMED_523_CAPACITOR_I24_1")
		)
		(pad "2" smd rect
			(at -0.5334 0 270)
			(size 0.7112 0.6096)
			(layers "B.Cu" "B.Mask" "B.Paste")
			(net "XP1R0V_SW")
		)
		(zone
			(layer "B.Cu")
			(hatch none 0.5)
			(connect_pads
				(clearance 0)
			)
			(min_thickness 0.25)
			(keepout
				(tracks allowed)
				(vias not_allowed)
				(pads allowed)
				(copperpour not_allowed)
				(footprints allowed)
			)
			(placement
				(enabled no)
				(sheetname "")
			)
			(fill
				(thermal_gap 0.5)
				(thermal_bridge_width 0.5)
				(island_removal_mode 0)
			)
			(polygon
				(pts
					(xy 139.6492 -52.0192) (xy 139.6492 -51.8668) (xy 140.2588 -51.8668) (xy 140.2588 -52.0192)
				)
			)
		)
	)
	(footprint ""
		(layer "B.Cu")
		(at 110.847124 -39.32301 90)
		(property "Reference" "C214"
			(at -1.14173 -42.016934 270)
			(unlocked yes)
			(layer "B.SilkS")
			(effects
				(font
					(size 0.635 0.4064)
					(thickness 0.1524)
				)
				(justify mirror)
			)
		)
		(property "Value" "VAL*"
			(at 0 3.718306 90)
			(unlocked yes)
			(layer "B.Fab")
			(hide yes)
			(effects
				(font
					(size 0.7874 0.5842)
					(thickness 0.127)
				)
				(justify mirror)
			)
		)
		(property "Tolerance" "TOL*"
			(at 0 4.861306 90)
			(unlocked yes)
			(layer "Cmts.User")
			(hide yes)
			(effects
				(font
					(size 0.7874 0.5842)
					(thickness 0.127)
				)
				(justify mirror)
			)
		)
		(property "User Part Number" "PARTNUM*"
			(at 0 2.575306 90)
			(unlocked yes)
			(layer "Cmts.User")
			(hide yes)
			(effects
				(font
					(size 0.7874 0.5842)
					(thickness 0.127)
				)
				(justify mirror)
			)
		)
		(property "Device Type" "CAPACITOR-G105-0B104-CK,0.1UF,A"
			(at 0 1.432306 90)
			(unlocked yes)
			(layer "B.Fab")
			(hide yes)
			(effects
				(font
					(size 0.7874 0.5842)
					(thickness 0.127)
				)
				(justify mirror)
			)
		)
		(duplicate_pad_numbers_are_jumpers no)
		(fp_line
			(start 0.970026 -0.4699)
			(end -0.970026 -0.4699)
			(stroke
				(width 0.1)
				(type default)
			)
			(layer "B.SilkS")
		)
		(fp_line
			(start -0.970026 -0.4699)
			(end -0.970026 0.4699)
			(stroke
				(width 0.1)
				(type default)
			)
			(layer "B.SilkS")
		)
		(fp_line
			(start 0.970026 0.4699)
			(end 0.970026 -0.4699)
			(stroke
				(width 0.1)
				(type default)
			)
			(layer "B.SilkS")
		)
		(fp_line
			(start -0.970026 0.4699)
			(end 0.970026 0.4699)
			(stroke
				(width 0.1)
				(type default)
			)
			(layer "B.SilkS")
		)
		(fp_poly
			(pts
				(xy 0.970026 0.4699) (xy -0.970026 0.4699) (xy -0.970026 -0.4699) (xy 0.970026 -0.4699)
			)
			(stroke
				(width 0)
				(type default)
			)
			(fill no)
			(layer "B.CrtYd")
		)
		(fp_line
			(start 0.508 -0.3048)
			(end -0.508 -0.3048)
			(stroke
				(width 0.1)
				(type default)
			)
			(layer "B.Fab")
		)
		(fp_line
			(start -0.508 -0.3048)
			(end -0.508 0.3048)
			(stroke
				(width 0.1)
				(type default)
			)
			(layer "B.Fab")
		)
		(fp_line
			(start 0.508 0.3048)
			(end 0.508 -0.3048)
			(stroke
				(width 0.1)
				(type default)
			)
			(layer "B.Fab")
		)
		(fp_line
			(start -0.508 0.3048)
			(end 0.508 0.3048)
			(stroke
				(width 0.1)
				(type default)
			)
			(layer "B.Fab")
		)
		(pad "1" smd circle
			(at 0.500126 0 270)
			(size 0.635 0.635)
			(layers "B.Cu" "B.Mask" "B.Paste")
			(net "XP1R0V_FPGA_VCCINT")
		)
		(pad "2" smd circle
			(at -0.500126 0 270)
			(size 0.635 0.635)
			(layers "B.Cu" "B.Mask" "B.Paste")
			(net "SG")
		)
	)
	(footprint ""
		(layer "B.Cu")
		(at 98.044 -96.774)
		(property "Reference" "R450"
			(at -0.889 -1.61163 0)
			(unlocked yes)
			(layer "B.SilkS")
			(effects
				(font
					(size 0.7874 0.5842)
					(thickness 0.1524)
				)
				(justify mirror)
			)
		)
		(property "Value" "VAL*"
			(at -0.02032 2.13233 0)
			(unlocked yes)
			(layer "B.Fab")
			(hide yes)
			(effects
				(font
					(size 0.7874 0.5842)
					(thickness 0.1524)
				)
				(justify mirror)
			)
		)
		(property "Tolerance" "TOL*"
			(at -0.044704 3.05435 0)
			(unlocked yes)
			(layer "Cmts.User")
			(hide yes)
			(effects
				(font
					(size 0.7874 0.5842)
					(thickness 0.1524)
				)
				(justify mirror)
			)
		)
		(property "User Part Number" "PARTNUM*"
			(at -0.02032 4.024884 0)
			(unlocked yes)
			(layer "Cmts.User")
			(hide yes)
			(effects
				(font
					(size 0.7874 0.5842)
					(thickness 0.1524)
				)
				(justify mirror)
			)
		)
		(property "Device Type" "RESISTOR-G155-14701-01,4.7KOHMA"
			(at -0.008382 1.210564 0)
			(unlocked yes)
			(layer "B.Fab")
			(hide yes)
			(effects
				(font
					(size 0.7874 0.5842)
					(thickness 0.1524)
				)
				(justify mirror)
			)
		)
		(duplicate_pad_numbers_are_jumpers no)
		(fp_line
			(start -1.143 -0.5588)
			(end 1.143 -0.5588)
			(stroke
				(width 0.1)
				(type default)
			)
			(layer "B.SilkS")
		)
		(fp_line
			(start -1.143 0.5588)
			(end -1.143 -0.5588)
			(stroke
				(width 0.1)
				(type default)
			)
			(layer "B.SilkS")
		)
		(fp_line
			(start 1.143 -0.5588)
			(end 1.143 0.5588)
			(stroke
				(width 0.1)
				(type default)
			)
			(layer "B.SilkS")
		)
		(fp_line
			(start 1.143 0.5588)
			(end -1.143 0.5588)
			(stroke
				(width 0.1)
				(type default)
			)
			(layer "B.SilkS")
		)
		(fp_poly
			(pts
				(xy 1.143 0.5588) (xy -1.143 0.5588) (xy -1.143 -0.5588) (xy 1.143 -0.5588)
			)
			(stroke
				(width 0)
				(type default)
			)
			(fill no)
			(layer "B.CrtYd")
		)
		(fp_line
			(start -0.508 -0.3048)
			(end 0.508 -0.3048)
			(stroke
				(width 0.1)
				(type default)
			)
			(layer "B.Fab")
		)
		(fp_line
			(start -0.508 0.3048)
			(end -0.508 -0.3048)
			(stroke
				(width 0.1)
				(type default)
			)
			(layer "B.Fab")
		)
		(fp_line
			(start 0.508 -0.3048)
			(end 0.508 0.3048)
			(stroke
				(width 0.1)
				(type default)
			)
			(layer "B.Fab")
		)
		(fp_line
			(start 0.508 0.3048)
			(end -0.508 0.3048)
			(stroke
				(width 0.1)
				(type default)
			)
			(layer "B.Fab")
		)
		(pad "1" smd rect
			(at 0.5334 0 180)
			(size 0.7112 0.6096)
			(layers "B.Cu" "B.Mask" "B.Paste")
			(net "MUX1_SEL")
		)
		(pad "2" smd rect
			(at -0.5334 0 180)
			(size 0.7112 0.6096)
			(layers "B.Cu" "B.Mask" "B.Paste")
			(net "XP3R3V_FPGA")
		)
		(zone
			(layer "B.Cu")
			(hatch none 0.5)
			(connect_pads
				(clearance 0)
			)
			(min_thickness 0.25)
			(keepout
				(tracks not_allowed)
				(vias allowed)
				(pads allowed)
				(copperpour not_allowed)
				(footprints allowed)
			)
			(placement
				(enabled no)
				(sheetname "")
			)
			(fill
				(thermal_gap 0.5)
				(thermal_bridge_width 0.5)
				(island_removal_mode 0)
			)
			(polygon
				(pts
					(xy 98.1202 -96.4692) (xy 98.1202 -97.0788) (xy 97.9678 -97.0788) (xy 97.9678 -96.4692)
				)
			)
		)
		(zone
			(layer "B.Cu")
			(hatch none 0.5)
			(connect_pads
				(clearance 0)
			)
			(min_thickness 0.25)
			(keepout
				(tracks allowed)
				(vias not_allowed)
				(pads allowed)
				(copperpour not_allowed)
				(footprints allowed)
			)
			(placement
				(enabled no)
				(sheetname "")
			)
			(fill
				(thermal_gap 0.5)
				(thermal_bridge_width 0.5)
				(island_removal_mode 0)
			)
			(polygon
				(pts
					(xy 98.1202 -96.4692) (xy 98.1202 -97.0788) (xy 97.9678 -97.0788) (xy 97.9678 -96.4692)
				)
			)
		)
	)
	(footprint ""
		(layer "B.Cu")
		(at 121.412 -46.789594 90)
		(property "Reference" "C145"
			(at -1.196594 1.49225 270)
			(unlocked yes)
			(layer "B.SilkS")
			(effects
				(font
					(size 0.635 0.4064)
					(thickness 0.1524)
				)
				(justify mirror)
			)
		)
		(property "Value" "VAL*"
			(at -0.0762 2.067306 90)
			(unlocked yes)
			(layer "B.Fab")
			(hide yes)
			(effects
				(font
					(size 0.7874 0.5842)
					(thickness 0.1524)
				)
				(justify mirror)
			)
		)
		(property "Tolerance" "TOL*"
			(at -0.0762 3.032506 90)
			(unlocked yes)
			(layer "Cmts.User")
			(hide yes)
			(effects
				(font
					(size 0.7874 0.5842)
					(thickness 0.1524)
				)
				(justify mirror)
			)
		)
		(property "User Part Number" "PARTNUM*"
			(at -0.1016 4.023106 90)
			(unlocked yes)
			(layer "Cmts.User")
			(hide yes)
			(effects
				(font
					(size 0.7874 0.5842)
					(thickness 0.1524)
				)
				(justify mirror)
			)
		)
		(property "Device Type" "CAPACITOR-G105-0B104-CK,0.1UF,A"
			(at -0.0508 1.127506 90)
			(unlocked yes)
			(layer "B.Fab")
			(hide yes)
			(effects
				(font
					(size 0.7874 0.5842)
					(thickness 0.1524)
				)
				(justify mirror)
			)
		)
		(duplicate_pad_numbers_are_jumpers no)
		(fp_line
			(start 1.143 -0.5588)
			(end 1.143 0.5588)
			(stroke
				(width 0.1)
				(type default)
			)
			(layer "B.SilkS")
		)
		(fp_line
			(start -1.143 -0.5588)
			(end 1.143 -0.5588)
			(stroke
				(width 0.1)
				(type default)
			)
			(layer "B.SilkS")
		)
		(fp_line
			(start 1.143 0.5588)
			(end -1.143 0.5588)
			(stroke
				(width 0.1)
				(type default)
			)
			(layer "B.SilkS")
		)
		(fp_line
			(start -1.143 0.5588)
			(end -1.143 -0.5588)
			(stroke
				(width 0.1)
				(type default)
			)
			(layer "B.SilkS")
		)
		(fp_rect
			(start -1.143 -0.5588)
			(end 1.143 0.5588)
			(stroke
				(width 0)
				(type default)
			)
			(fill no)
			(layer "B.CrtYd")
		)
		(fp_line
			(start 0.508 -0.3048)
			(end 0.508 0.3048)
			(stroke
				(width 0.1)
				(type default)
			)
			(layer "B.Fab")
		)
		(fp_line
			(start -0.508 -0.3048)
			(end 0.508 -0.3048)
			(stroke
				(width 0.1)
				(type default)
			)
			(layer "B.Fab")
		)
		(fp_line
			(start 0.508 0.3048)
			(end -0.508 0.3048)
			(stroke
				(width 0.1)
				(type default)
			)
			(layer "B.Fab")
		)
		(fp_line
			(start -0.508 0.3048)
			(end -0.508 -0.3048)
			(stroke
				(width 0.1)
				(type default)
			)
			(layer "B.Fab")
		)
		(pad "1" smd rect
			(at 0.5334 0 270)
			(size 0.7112 0.6096)
			(layers "B.Cu" "B.Mask" "B.Paste")
			(net "XP3R3V_FPGA")
		)
		(pad "2" smd rect
			(at -0.5334 0 270)
			(size 0.7112 0.6096)
			(layers "B.Cu" "B.Mask" "B.Paste")
			(net "SG")
		)
		(zone
			(layer "B.Cu")
			(hatch none 0.5)
			(connect_pads
				(clearance 0)
			)
			(min_thickness 0.25)
			(keepout
				(tracks allowed)
				(vias not_allowed)
				(pads allowed)
				(copperpour not_allowed)
				(footprints allowed)
			)
			(placement
				(enabled no)
				(sheetname "")
			)
			(fill
				(thermal_gap 0.5)
				(thermal_bridge_width 0.5)
				(island_removal_mode 0)
			)
			(polygon
				(pts
					(xy 121.1072 -46.713394) (xy 121.7168 -46.713394) (xy 121.7168 -46.865794) (xy 121.1072 -46.865794)
				)
			)
		)
	)
	(footprint ""
		(layer "B.Cu")
		(at 138.811 -59.563 90)
		(property "Reference" "R247"
			(at 3.175 -0.03937 270)
			(unlocked yes)
			(layer "B.SilkS")
			(effects
				(font
					(size 0.7874 0.5842)
					(thickness 0.1524)
				)
				(justify mirror)
			)
		)
		(property "Value" "VAL*"
			(at -0.02032 2.13233 90)
			(unlocked yes)
			(layer "B.Fab")
			(hide yes)
			(effects
				(font
					(size 0.7874 0.5842)
					(thickness 0.1524)
				)
				(justify mirror)
			)
		)
		(property "Tolerance" "TOL*"
			(at -0.044704 3.05435 90)
			(unlocked yes)
			(layer "Cmts.User")
			(hide yes)
			(effects
				(font
					(size 0.7874 0.5842)
					(thickness 0.1524)
				)
				(justify mirror)
			)
		)
		(property "User Part Number" "PARTNUM*"
			(at -0.02032 4.024884 90)
			(unlocked yes)
			(layer "Cmts.User")
			(hide yes)
			(effects
				(font
					(size 0.7874 0.5842)
					(thickness 0.1524)
				)
				(justify mirror)
			)
		)
		(property "Device Type" "RESISTOR-G155-11002-01,10KOHM,A"
			(at -0.008382 1.210564 90)
			(unlocked yes)
			(layer "B.Fab")
			(hide yes)
			(effects
				(font
					(size 0.7874 0.5842)
					(thickness 0.1524)
				)
				(justify mirror)
			)
		)
		(duplicate_pad_numbers_are_jumpers no)
		(fp_line
			(start 1.143 -0.5588)
			(end 1.143 0.5588)
			(stroke
				(width 0.1)
				(type default)
			)
			(layer "B.SilkS")
		)
		(fp_line
			(start -1.143 -0.5588)
			(end 1.143 -0.5588)
			(stroke
				(width 0.1)
				(type default)
			)
			(layer "B.SilkS")
		)
		(fp_line
			(start 1.143 0.5588)
			(end -1.143 0.5588)
			(stroke
				(width 0.1)
				(type default)
			)
			(layer "B.SilkS")
		)
		(fp_line
			(start -1.143 0.5588)
			(end -1.143 -0.5588)
			(stroke
				(width 0.1)
				(type default)
			)
			(layer "B.SilkS")
		)
		(fp_poly
			(pts
				(xy 1.143 0.5588) (xy -1.143 0.5588) (xy -1.143 -0.5588) (xy 1.143 -0.5588)
			)
			(stroke
				(width 0)
				(type default)
			)
			(fill no)
			(layer "B.CrtYd")
		)
		(fp_line
			(start 0.508 -0.3048)
			(end 0.508 0.3048)
			(stroke
				(width 0.1)
				(type default)
			)
			(layer "B.Fab")
		)
		(fp_line
			(start -0.508 -0.3048)
			(end 0.508 -0.3048)
			(stroke
				(width 0.1)
				(type default)
			)
			(layer "B.Fab")
		)
		(fp_line
			(start 0.508 0.3048)
			(end -0.508 0.3048)
			(stroke
				(width 0.1)
				(type default)
			)
			(layer "B.Fab")
		)
		(fp_line
			(start -0.508 0.3048)
			(end -0.508 -0.3048)
			(stroke
				(width 0.1)
				(type default)
			)
			(layer "B.Fab")
		)
		(pad "1" smd rect
			(at 0.5334 0 270)
			(size 0.7112 0.6096)
			(layers "B.Cu" "B.Mask" "B.Paste")
			(net "VIN_XP1R0V")
		)
		(pad "2" smd rect
			(at -0.5334 0 270)
			(size 0.7112 0.6096)
			(layers "B.Cu" "B.Mask" "B.Paste")
			(net "UNNAMED_523_CAPACITOR_I7_1")
		)
		(zone
			(layer "B.Cu")
			(hatch none 0.5)
			(connect_pads
				(clearance 0)
			)
			(min_thickness 0.25)
			(keepout
				(tracks not_allowed)
				(vias allowed)
				(pads allowed)
				(copperpour not_allowed)
				(footprints allowed)
			)
			(placement
				(enabled no)
				(sheetname "")
			)
			(fill
				(thermal_gap 0.5)
				(thermal_bridge_width 0.5)
				(island_removal_mode 0)
			)
			(polygon
				(pts
					(xy 139.1158 -59.6392) (xy 138.5062 -59.6392) (xy 138.5062 -59.4868) (xy 139.1158 -59.4868)
				)
			)
		)
		(zone
			(layer "B.Cu")
			(hatch none 0.5)
			(connect_pads
				(clearance 0)
			)
			(min_thickness 0.25)
			(keepout
				(tracks allowed)
				(vias not_allowed)
				(pads allowed)
				(copperpour not_allowed)
				(footprints allowed)
			)
			(placement
				(enabled no)
				(sheetname "")
			)
			(fill
				(thermal_gap 0.5)
				(thermal_bridge_width 0.5)
				(island_removal_mode 0)
			)
			(polygon
				(pts
					(xy 139.1158 -59.6392) (xy 138.5062 -59.6392) (xy 138.5062 -59.4868) (xy 139.1158 -59.4868)
				)
			)
		)
	)
)
